# T6G (Grand Teton) — schematic netlist excerpt (pin names and nets, part order shuffled) for the footprints in the layout excerpt that follows; sources: Cadence DE-HDL packaged netlist, KiCad conversion of 04192023_DAF0TMB3IC0_F0TG_MB_C_brd_V02_OCP.brd

R3066  Q_RES  33.2 1% CHIP  pkg 0402LF  page 81 : A = FM_SMB_1_ALERT_GPU_ISO_R_N ; B = FM_SMB_1_ALERT_GPU_ISO_N
C2043  Q_CAP  100PF 50V 5% EMPTY  pkg 0402  page 257 : A = P3V3_ADC_MAM ; B = GND

(kicad_pcb
	(version 20260206)
	(generator "pcbnew")
	(generator_version "10.0")
	(general
		(thickness 1.6)
		(legacy_teardrops no)
	)
	(paper "A4")
	(title_block
		(title "04192023_DAF0TMB3IC0_F0TG_MB_C_brd_V02_OCP.brd")
		(comment 1 "Grand Teton / footprints 1401-1402 of 8354")
	)
	(layers
		(0 "F.Cu" signal "TOP")
		(4 "In1.Cu" signal "GND")
		(6 "In2.Cu" signal "IN1")
		(8 "In3.Cu" signal "GND1")
		(10 "In4.Cu" signal "IN2")
		(12 "In5.Cu" signal "GND2")
		(14 "In6.Cu" signal "IN3")
		(16 "In7.Cu" signal "GND3")
		(18 "In8.Cu" signal "VCC")
		(20 "In9.Cu" signal "VCC1")
		(22 "In10.Cu" signal "GND4")
		(24 "In11.Cu" signal "IN4")
		(26 "In12.Cu" signal "GND5")
		(28 "In13.Cu" signal "IN5")
		(30 "In14.Cu" signal "GND6")
		(32 "In15.Cu" signal "IN6")
		(34 "In16.Cu" signal "GND7")
		(2 "B.Cu" signal "BOTTOM")
		(9 "F.Adhes" user "F.Adhesive")
		(11 "B.Adhes" user "B.Adhesive")
		(13 "F.Paste" user "Package Geometry/Pastemask Top")
		(15 "B.Paste" user "Package Geometry/Pastemask Bottom")
		(5 "F.SilkS" user "Ref Des/Silkscreen Top")
		(7 "B.SilkS" user "Ref Des/Silkscreen Bottom")
		(1 "F.Mask" user "Board Geometry/Soldermask Top")
		(3 "B.Mask" user "Board Geometry/Soldermask Bottom")
		(17 "Dwgs.User" user "User.Drawings")
		(19 "Cmts.User" user "User.Comments")
		(21 "Eco1.User" user "User.Eco1")
		(23 "Eco2.User" user "User.Eco2")
		(25 "Edge.Cuts" user "Board Geometry/Outline")
		(27 "Margin" user)
		(31 "F.CrtYd" user "Package Geometry/Place Bound Top")
		(29 "B.CrtYd" user "Package Geometry/Place Bound Bottom")
		(35 "F.Fab" user "Ref Des/Assembly Top")
		(33 "B.Fab" user "Ref Des/Assembly Bottom")
	)
	(footprint ""
		(layer "F.Cu")
		(at 205.214982 -119.721376)
		(property "Reference" "R3066"
			(at 0 0 0)
			(layer "F.SilkS")
			(hide yes)
			(effects
				(font
					(size 1.27 1.27)
				)
			)
		)
		(property "Value" ""
			(at 0 0 0)
			(layer "F.Fab")
			(effects
				(font
					(size 1.27 1.27)
				)
			)
		)
		(duplicate_pad_numbers_are_jumpers no)
		(fp_line
			(start -0.7874 -0.4064)
			(end 0.7874 -0.4064)
			(stroke
				(width 0.1524)
				(type default)
			)
			(layer "F.SilkS")
		)
		(fp_line
			(start -0.7874 0.4064)
			(end -0.7874 -0.4064)
			(stroke
				(width 0.1524)
				(type default)
			)
			(layer "F.SilkS")
		)
		(fp_line
			(start 0.7874 -0.4064)
			(end 0.7874 0.4064)
			(stroke
				(width 0.1524)
				(type default)
			)
			(layer "F.SilkS")
		)
		(fp_line
			(start 0.7874 0.4064)
			(end -0.7874 0.4064)
			(stroke
				(width 0.1524)
				(type default)
			)
			(layer "F.SilkS")
		)
		(fp_line
			(start -0.67945 -0.305054)
			(end -0.12065 -0.305054)
			(stroke
				(width 0.1)
				(type default)
			)
			(layer "F.Fab")
		)
		(fp_line
			(start -0.67945 0.3048)
			(end -0.67945 -0.305054)
			(stroke
				(width 0.1)
				(type default)
			)
			(layer "F.Fab")
		)
		(fp_line
			(start -0.12065 -0.305054)
			(end -0.12065 -0.2794)
			(stroke
				(width 0.1)
				(type default)
			)
			(layer "F.Fab")
		)
		(fp_line
			(start -0.12065 -0.2794)
			(end 0.12065 -0.2794)
			(stroke
				(width 0.1)
				(type default)
			)
			(layer "F.Fab")
		)
		(fp_line
			(start -0.12065 0.2794)
			(end -0.12065 0.3048)
			(stroke
				(width 0.1)
				(type default)
			)
			(layer "F.Fab")
		)
		(fp_line
			(start -0.12065 0.3048)
			(end -0.67945 0.3048)
			(stroke
				(width 0.1)
				(type default)
			)
			(layer "F.Fab")
		)
		(fp_line
			(start 0.120396 0.2794)
			(end -0.12065 0.2794)
			(stroke
				(width 0.1)
				(type default)
			)
			(layer "F.Fab")
		)
		(fp_line
			(start 0.120396 0.3048)
			(end 0.120396 0.2794)
			(stroke
				(width 0.1)
				(type default)
			)
			(layer "F.Fab")
		)
		(fp_line
			(start 0.12065 -0.3048)
			(end 0.67945 -0.3048)
			(stroke
				(width 0.1)
				(type default)
			)
			(layer "F.Fab")
		)
		(fp_line
			(start 0.12065 -0.2794)
			(end 0.12065 -0.3048)
			(stroke
				(width 0.1)
				(type default)
			)
			(layer "F.Fab")
		)
		(fp_line
			(start 0.67945 -0.3048)
			(end 0.67945 0.3048)
			(stroke
				(width 0.1)
				(type default)
			)
			(layer "F.Fab")
		)
		(fp_line
			(start 0.67945 0.3048)
			(end 0.120396 0.3048)
			(stroke
				(width 0.1)
				(type default)
			)
			(layer "F.Fab")
		)
		(pad "1" smd circle
			(at -0.40005 0)
			(size 0 0)
			(layers "F.Cu" "F.Mask" "F.Paste")
			(net "FM_SMB_1_ALERT_GPU_ISO_R_N")
		)
		(pad "2" smd circle
			(at 0.40005 0)
			(size 0 0)
			(layers "F.Cu" "F.Mask" "F.Paste")
			(net "FM_SMB_1_ALERT_GPU_ISO_N")
		)
	)
	(footprint ""
		(layer "F.Cu")
		(at 329.360022 -31.937706)
		(property "Reference" "C2043"
			(at 0 0 0)
			(layer "F.SilkS")
			(hide yes)
			(effects
				(font
					(size 1.27 1.27)
				)
			)
		)
		(property "Value" ""
			(at 0 0 0)
			(layer "F.Fab")
			(effects
				(font
					(size 1.27 1.27)
				)
			)
		)
		(duplicate_pad_numbers_are_jumpers no)
		(fp_line
			(start -0.7874 -0.4064)
			(end 0.7874 -0.4064)
			(stroke
				(width 0.1524)
				(type default)
			)
			(layer "F.SilkS")
		)
		(fp_line
			(start -0.7874 0.4064)
			(end -0.7874 -0.4064)
			(stroke
				(width 0.1524)
				(type default)
			)
			(layer "F.SilkS")
		)
		(fp_line
			(start 0.7874 -0.4064)
			(end 0.7874 0.4064)
			(stroke
				(width 0.1524)
				(type default)
			)
			(layer "F.SilkS")
		)
		(fp_line
			(start 0.7874 0.4064)
			(end -0.7874 0.4064)
			(stroke
				(width 0.1524)
				(type default)
			)
			(layer "F.SilkS")
		)
		(fp_line
			(start -0.67945 -0.305054)
			(end -0.12065 -0.305054)
			(stroke
				(width 0.1)
				(type default)
			)
			(layer "F.Fab")
		)
		(fp_line
			(start -0.67945 0.3048)
			(end -0.67945 -0.305054)
			(stroke
				(width 0.1)
				(type default)
			)
			(layer "F.Fab")
		)
		(fp_line
			(start -0.12065 -0.305054)
			(end -0.12065 -0.2794)
			(stroke
				(width 0.1)
				(type default)
			)
			(layer "F.Fab")
		)
		(fp_line
			(start -0.12065 -0.2794)
			(end 0.12065 -0.2794)
			(stroke
				(width 0.1)
				(type default)
			)
			(layer "F.Fab")
		)
		(fp_line
			(start -0.12065 0.2794)
			(end -0.12065 0.3048)
			(stroke
				(width 0.1)
				(type default)
			)
			(layer "F.Fab")
		)
		(fp_line
			(start -0.12065 0.3048)
			(end -0.67945 0.3048)
			(stroke
				(width 0.1)
				(type default)
			)
			(layer "F.Fab")
		)
		(fp_line
			(start 0.120396 0.2794)
			(end -0.12065 0.2794)
			(stroke
				(width 0.1)
				(type default)
			)
			(layer "F.Fab")
		)
		(fp_line
			(start 0.120396 0.3048)
			(end 0.120396 0.2794)
			(stroke
				(width 0.1)
				(type default)
			)
			(layer "F.Fab")
		)
		(fp_line
			(start 0.12065 -0.3048)
			(end 0.67945 -0.3048)
			(stroke
				(width 0.1)
				(type default)
			)
			(layer "F.Fab")
		)
		(fp_line
			(start 0.12065 -0.2794)
			(end 0.12065 -0.3048)
			(stroke
				(width 0.1)
				(type default)
			)
			(layer "F.Fab")
		)
		(fp_line
			(start 0.67945 -0.3048)
			(end 0.67945 0.3048)
			(stroke
				(width 0.1)
				(type default)
			)
			(layer "F.Fab")
		)
		(fp_line
			(start 0.67945 0.3048)
			(end 0.120396 0.3048)
			(stroke
				(width 0.1)
				(type default)
			)
			(layer "F.Fab")
		)
		(pad "1" smd circle
			(at -0.40005 0)
			(size 0 0)
			(layers "F.Cu" "F.Mask" "F.Paste")
			(net "P3V3_ADC_MAM")
		)
		(pad "2" smd circle
			(at 0.40005 0)
			(size 0 0)
			(layers "F.Cu" "F.Mask" "F.Paste")
			(net "GND")
		)
	)
)
